# T6G (Grand Teton) — schematic parts with pin connectivity, parts 8222–8226 of 8303; source: Cadence DE-HDL packaged netlist (pstxprt.dat, pstxnet.dat, pstchip.dat)

U6002  TUSB8042AIRGCR  IC  pkg VQFN64_TH_0-5_9X9XC  page 178
  1  USB_DP_DN1  BI  = USB_HUB2_TI_USB_DP_DN1_MRP_CFG_STRAP
  2  USB_DM_DN1  BI  = NC
  3  USB_SSTXP_DN1  OUT  = NC
  4  USB_SSTXM_DN1  OUT  = NC
  5  VDD_5  POWER  = USB_HUB2_TI_VDD_MRP_USB3DN_TXDM1
  6  USB_SSRXP_DN1  IN  = USB_HUB2_TI_USB_SSRXP_DN1_MRP_VDD12
  7  USB_SSRXM_DN1  IN  = NC
  8  VDD_8  POWER  = USB_HUB2_TI_VDD_MRP_USB3DN_RXDM1
  9  USB_DP_DN2  BI  = USB2_CPU0_P0_HUB2_R_DP
  10  USB_DM_DN2  BI  = USB2_CPU0_P0_HUB2_R_DN
  11  USB_SSTXP_DN2  OUT  = USB3_CPU0_BMC_HUB2_TX_DP
  12  USB_SSTXM_DN2  OUT  = USB3_CPU0_BMC_HUB2_TX_DN
  13  VDD_13  POWER  = P1V2_CPU0_USB2_DVDD12
  14  USB_SSRXP_DN2  IN  = USB3_CPU0_BMC_RX_C2_DP
  15  USB_SSRXM_DN2  IN  = USB3_CPU0_BMC_RX_C2_DN
  16  VDD33_16  POWER  = USB_HUB2_TI_VDD33_MRP_PROG_FUNC7
  17  USB_DP_DN3  BI  = USB_HUB2_TI_USB_DP_DN3_MRP_VDD12
  18  USB_DM_DN3  BI  = USB_HUB2_TI_USB_DM_DN3_MRP_VDD33
  19  USB_SSTXP_DN3  OUT  = NC
  20  USB_SSTXM_DN3  OUT  = NC
  21  VDD_21  POWER  = USB_HUB2_TI_VDD_MRP_USB3DN_TXDP3
  22  USB_SSRXP_DN3  IN  = NC
  23  USB_SSRXM_DN3  IN  = USB_HUB2_TI_USB_SSRXM_DN3_MRP_VDD12
  24  USB_DP_DN4  BI  = NC
  25  USB_DM_DN4  BI  = NC
  26  USB_SSTXP_DN4  OUT  = NC
  27  USB_SSTXM_DN4  OUT  = NC
  28  VDD_28  POWER  = USB_HUB2_TI_VDD_MRP_USB3DN_TXDP4
  29  USB_SSRXP_DN4  IN  = NC
  30  USB_SSRXM_DN4  IN  = USB_HUB2_TI_USB_SSRXM_DN4_MRP_VDD12
  31  VDD_31  POWER  = USB_HUB2_TI_VDD_MRP_USB3DN_RXDP4
  32  \pwrctl4||baten4\  BI  = NC
  33  \pwrctl3||baten3\  BI  = USB_HUB2_TI_PWRCTL3_MRP_VDD33
  34  VDD33_34  POWER  = USB_HUB2_TI_VDD33_MRP_PRT_CTL4_GANGPWR
  35  \pwrctl2||baten2\  BI  = USB_HUB2_TI_PWRCTL2_MRP_VDD12
  36  \pwrctl1||baten1\  BI  = NC
  37  \sda||smbdat\  BI  = SMB_USB_HUB2_TI_SDA_MRP_PRT_CTL2
  38  \scl||smbclk\  BI  = SMB_USB_HUB2_TI_SCL_MRP_PRT_CTL1
  39  \smbusz||ss_suspend\  BI  = USB_HUB2_TI_SMBUSZ_MRP_PROG_FUNC2
  40  \fullpwrmgmtz||fullautoz||smba1||ss_up\  BI  = USB_HUB2_TI_FULLPWRMGMTZ_MRP_PROG_FUNC3
  41  PWRCTL_POL  BI  = USB_HUB2_TI_PWRCTL_POL_MRP_VBUS_DET
  42  \ganged||smba2||hs_up\  BI  = USB_HUB2_TI_GANGED_MRP_I2C_SLV_CFG0
  43  OVERCUR4Z  IN  = USB_HUB2_TI_OVERCUR4_MRP_I2C_SLV_CFG1
  44  OVERCUR3Z  IN  = USB_HUB2_TI_OVERCUR3_MRP_CFG_BC_EN
  45  \autoenz||hs_suspend\  BI  = USB_HUB2_TI_HS_SUSPEND_MRP_CFG_NON_REM
  46  OVERCUR1Z  IN  = USB_HUB2_TI_OVERCUR1_MRP_PROG_FUNC4
  47  OVERCUR2Z  IN  = USB_HUB2_TI_OVERCUR2_MRP_PROG_FUNC5
  48  USB_VBUS  IN  = USB_HUB2_TI_USB_VBUS_MRP_RESET_N
  49  TEST  IN  = USB_HUB2_TI_TEST_MRP_PROG_FUNC6
  50  GRSTZ  IN  = USB_HUB2_TI_GRSTZ_MRP_PROG_FUNC1
  51  VDD_51  POWER  = P1V2_CPU0_USB2_DVDD12
  52  VDD33_52  POWER  = P3V3_AUX_CPU0_USB2_AVDD33
  53  USB_DP_UP  BI  = USB2_CPU0_P0_R2_DP
  54  USB_DM_UP  BI  = USB2_CPU0_P0_R2_DN
  55  USB_SSTXP_UP  OUT  = USB3_CPU0_BMC_RX_HUB2_DP
  56  USB_SSTXM_UP  OUT  = USB3_CPU0_BMC_RX_HUB2_DN
  57  VDD_57  POWER  = P1V2_CPU0_USB2_DVDD12
  58  USB_SSRXP_UP  IN  = USB3_CPU0_BMC_TX_C2_DP
  59  USB_SSRXM_UP  IN  = USB3_CPU0_BMC_TX_C2_DN
  60  NC_1  TRI  = USB_HUB2_TI_NC_MRP_ATEST
  61  XO  OUT  = XTAL_USB_CPU0_HUB2_XOUT
  62  XI  IN  = XTAL_USB_CPU0_HUB2_XIN
  63  VDD33_63  POWER  = P3V3_AUX_CPU0_USB2_AVDD33
  64  USB_R1  IN  = USB_HUB2_TI_USB_R1_MRP_RBIAS
  TH  TH_VSS  POWER  = GND

U6003  M24128BWMN6TP  M24128-BWMN6TP IC  pkg SOIC8XH  page 176
  1  E0  IN  = USB_CPU0_ADD_A0
  2  E1  IN  = USB_CPU0_ADD_A1
  3  E2  IN  = USB_CPU0_ADD_A2
  4  VSS  POWER  = GND
  5  SDA  BI  = SMB_USB_CPU0_HUB1_SDA_R2
  6  SCL  IN  = SMB_USB_CPU0_HUB1_SCL_R2
  7  \wc#\  IN  = PD_USB_CPU0_WP
  8  VCC  POWER  = P3V3_AUX

U6004  MOSFET_NCH_GDS_ESD_PROTECTED  2N7002K EMPTY  pkg SOT23_GDSXC  page 267
  D  D  BI  = A_HSC_LOW_DRAIN
  G  G  IN  = A_HSC_LOW_GATE
  S  S  BI  = GND

U6005  ISL28022FRZT  ISL28022FRZ-T IC  pkg QFN16_TH_0-5_3X3XH  page 271
  1  A1  IN  = HSC_TYPE_ADC_A1
  2  A0  IN  = HSC_TYPE_ADC_A0
  3  \ext_clk||int\  BI  = HSC_TYPE_ADC_ALERT
  4  \sda||smbdat\  BI  = SMB_HSC_TYPE_ADC_SDA
  5  \scl|||smbclk\  IN  = SMB_HSC_TYPE_ADC_SCL
  6  NC0  TRI  = NC_HSC_TYPE_NC0
  7  NC1  TRI  = NC_HSC_TYPE_NC1
  8  NC2  TRI  = NC_HSC_TYPE_NC2
  9  VCC  POWER  = P3V3_AUX
  10  GND  POWER  = GND
  11  VBUS  POWER  = HSC_TYPE_ADC
  12  VINM  IN  = NC_HSC_TYPE_VINM
  13  VINP  IN  = NC_HSC_TYPE_VINP
  14  NC3  TRI  = NC_HSC_TYPE_NC3
  15  NC4  TRI  = NC_HSC_TYPE_NC4
  16  NC5  TRI  = NC_HSC_TYPE_NC5
  TH  TH_GND  POWER  = GND

U6006  APX80929SAG7  APX809-29SAG-7 IC  pkg SOT23_123XI  page 188
  1  GND  POWER  = GND
  2  RESET_L  OUT  = PWRGD_P3V3_EN_R
  3  VCC  POWER  = P3V3
